(kicad_pcb
	(version 20260206)
	(generator "pcbnew")
	(generator_version "10.0")
	(general
		(thickness 1.6)
		(legacy_teardrops no)
	)
	(paper "A4")
	(title_block
		(title "12092022_DA0F0TMDCD0_F0T_Management_Board_D_brd_V3_OCP.brd")
		(comment 1 "Grand Teton / footprints 709-714 of 1440")
	)
	(layers
		(0 "F.Cu" signal "TOP")
		(4 "In1.Cu" signal "GND")
		(6 "In2.Cu" signal "IN1")
		(8 "In3.Cu" signal "GND1")
		(10 "In4.Cu" signal "IN2")
		(12 "In5.Cu" signal "VCC")
		(14 "In6.Cu" signal "VCC1")
		(16 "In7.Cu" signal "IN3")
		(18 "In8.Cu" signal "GND2")
		(20 "In9.Cu" signal "IN4")
		(22 "In10.Cu" signal "GND3")
		(2 "B.Cu" signal "BOTTOM")
		(9 "F.Adhes" user "F.Adhesive")
		(11 "B.Adhes" user "B.Adhesive")
		(13 "F.Paste" user "Package Geometry/Pastemask Top")
		(15 "B.Paste" user "Package Geometry/Pastemask Bottom")
		(5 "F.SilkS" user "Ref Des/Silkscreen Top")
		(7 "B.SilkS" user "Ref Des/Silkscreen Bottom")
		(1 "F.Mask" user "Board Geometry/Soldermask Top")
		(3 "B.Mask" user "Board Geometry/Soldermask Bottom")
		(17 "Dwgs.User" user "User.Drawings")
		(19 "Cmts.User" user "User.Comments")
		(21 "Eco1.User" user "User.Eco1")
		(23 "Eco2.User" user "User.Eco2")
		(25 "Edge.Cuts" user "Board Geometry/Outline")
		(27 "Margin" user)
		(31 "F.CrtYd" user "Package Geometry/Place Bound Top")
		(29 "B.CrtYd" user "Package Geometry/Place Bound Bottom")
		(35 "F.Fab" user "Ref Des/Assembly Top")
		(33 "B.Fab" user "Ref Des/Assembly Bottom")
	)
	(footprint ""
		(layer "F.Cu")
		(at 114.554 -3.048 -90)
		(property "Reference" "X6"
			(at -1.73863 -0.8382 0)
			(unlocked yes)
			(layer "F.SilkS")
			(effects
				(font
					(size 0.7874 0.5842)
					(thickness 0.1524)
				)
				(justify left)
			)
		)
		(property "Value" ""
			(at 0 0 270)
			(layer "F.Fab")
			(effects
				(font
					(size 1.27 1.27)
				)
			)
		)
		(property "Device Type" "TP_TDR_4P_FTS_TH-TP_TDR_4P_DIPA"
			(at 1.30175 1.27 0)
			(unlocked yes)
			(layer "F.Fab")
			(hide yes)
			(effects
				(font
					(size 0.635 0.4064)
					(thickness 0.1524)
				)
			)
		)
		(property "User Part Number" "N_A"
			(at 1.30175 1.27 0)
			(unlocked yes)
			(layer "Cmts.User")
			(hide yes)
			(effects
				(font
					(size 0.635 0.4064)
					(thickness 0.1524)
				)
			)
		)
		(duplicate_pad_numbers_are_jumpers no)
		(fp_line
			(start 0 3.81)
			(end 2.54 3.81)
			(stroke
				(width 0.1524)
				(type default)
			)
			(layer "F.SilkS")
		)
		(fp_line
			(start 2.54 3.81)
			(end 2.54 3.6703)
			(stroke
				(width 0.1524)
				(type default)
			)
			(layer "F.SilkS")
		)
		(fp_line
			(start 0 3.175)
			(end 0 3.81)
			(stroke
				(width 0.1524)
				(type default)
			)
			(layer "F.SilkS")
		)
		(fp_line
			(start 2.54 1.4097)
			(end 2.54 1.1303)
			(stroke
				(width 0.1524)
				(type default)
			)
			(layer "F.SilkS")
		)
		(fp_line
			(start 0 0.635)
			(end 0 1.905)
			(stroke
				(width 0.1524)
				(type default)
			)
			(layer "F.SilkS")
		)
		(fp_line
			(start 2.54 -1.1303)
			(end 2.54 -1.27)
			(stroke
				(width 0.1524)
				(type default)
			)
			(layer "F.SilkS")
		)
		(fp_line
			(start 0 -1.27)
			(end 0 -0.635)
			(stroke
				(width 0.1524)
				(type default)
			)
			(layer "F.SilkS")
		)
		(fp_line
			(start 2.54 -1.27)
			(end 0 -1.27)
			(stroke
				(width 0.1524)
				(type default)
			)
			(layer "F.SilkS")
		)
		(fp_poly
			(pts
				(xy -0.761746 0) (xy -2.285746 -0.762) (xy -2.285746 0.762)
			)
			(stroke
				(width 0)
				(type default)
			)
			(fill yes)
			(layer "F.SilkS")
		)
		(fp_line
			(start 0 3.81)
			(end 2.54 3.81)
			(stroke
				(width 0.1)
				(type default)
			)
			(layer "F.Fab")
		)
		(fp_line
			(start 2.54 3.81)
			(end 2.54 -1.27)
			(stroke
				(width 0.1)
				(type default)
			)
			(layer "F.Fab")
		)
		(fp_line
			(start 0 -1.27)
			(end 0 3.81)
			(stroke
				(width 0.1)
				(type default)
			)
			(layer "F.Fab")
		)
		(fp_line
			(start 2.54 -1.27)
			(end 0 -1.27)
			(stroke
				(width 0.1)
				(type default)
			)
			(layer "F.Fab")
		)
		(fp_poly
			(pts
				(xy -0.761746 0) (xy -2.285746 -0.762) (xy -2.285746 0.762)
			)
			(stroke
				(width 0)
				(type default)
			)
			(fill yes)
			(layer "F.Fab")
		)
		(pad "1" thru_hole circle
			(at 0 0 270)
			(size 1.0033 1.0033)
			(drill 0.249936)
			(layers "*.Cu" "*.Mask")
			(remove_unused_layers no)
			(net "TDR_DIFF_85_BOT_DP")
			(clearance 0.10795)
			(thermal_gap 0.10795)
			(padstack
				(mode front_inner_back)
				(layer "Inner"
					(shape circle)
					(size 0.8001 0.8001)
					(clearance 0.1524)
				)
				(layer "B.Cu"
					(shape circle)
					(size 1.0033 1.0033)
					(clearance 0.10795)
				)
			)
		)
		(pad "2" thru_hole circle
			(at 2.54 0 270)
			(size 1.9939 1.9939)
			(drill 0.249936)
			(layers "*.Cu" "*.Mask")
			(remove_unused_layers no)
			(net "GND_P1")
			(clearance 0.10795)
			(thermal_gap 0.10795)
			(padstack
				(mode front_inner_back)
				(layer "Inner"
					(shape circle)
					(size 0.8001 0.8001)
					(clearance 0.1524)
				)
				(layer "B.Cu"
					(shape circle)
					(size 1.9939 1.9939)
					(clearance 0.10795)
				)
			)
		)
		(pad "3" thru_hole circle
			(at 2.54 2.54 270)
			(size 1.9939 1.9939)
			(drill 0.249936)
			(layers "*.Cu" "*.Mask")
			(remove_unused_layers no)
			(net "GND_P1")
			(clearance 0.10795)
			(thermal_gap 0.10795)
			(padstack
				(mode front_inner_back)
				(layer "Inner"
					(shape circle)
					(size 0.8001 0.8001)
					(clearance 0.1524)
				)
				(layer "B.Cu"
					(shape circle)
					(size 1.9939 1.9939)
					(clearance 0.10795)
				)
			)
		)
		(pad "4" thru_hole circle
			(at 0 2.54 270)
			(size 1.0033 1.0033)
			(drill 0.249936)
			(layers "*.Cu" "*.Mask")
			(remove_unused_layers no)
			(net "TDR_DIFF_85_BOT_DN")
			(clearance 0.10795)
			(thermal_gap 0.10795)
			(padstack
				(mode front_inner_back)
				(layer "Inner"
					(shape circle)
					(size 0.8001 0.8001)
					(clearance 0.1524)
				)
				(layer "B.Cu"
					(shape circle)
					(size 1.0033 1.0033)
					(clearance 0.10795)
				)
			)
		)
	)
	(footprint ""
		(layer "F.Cu")
		(at 9.1694 -105.5878)
		(property "Reference" "C215"
			(at 0 0 0)
			(layer "F.SilkS")
			(hide yes)
			(effects
				(font
					(size 1.27 1.27)
				)
			)
		)
		(property "Value" ""
			(at 0 0 0)
			(layer "F.Fab")
			(effects
				(font
					(size 1.27 1.27)
				)
			)
		)
		(duplicate_pad_numbers_are_jumpers no)
		(fp_line
			(start -0.7874 -0.4064)
			(end 0.7874 -0.4064)
			(stroke
				(width 0.1524)
				(type default)
			)
			(layer "F.SilkS")
		)
		(fp_line
			(start -0.7874 0.4064)
			(end -0.7874 -0.4064)
			(stroke
				(width 0.1524)
				(type default)
			)
			(layer "F.SilkS")
		)
		(fp_line
			(start 0.7874 -0.4064)
			(end 0.7874 0.4064)
			(stroke
				(width 0.1524)
				(type default)
			)
			(layer "F.SilkS")
		)
		(fp_line
			(start 0.7874 0.4064)
			(end -0.7874 0.4064)
			(stroke
				(width 0.1524)
				(type default)
			)
			(layer "F.SilkS")
		)
		(fp_line
			(start -0.67945 -0.305054)
			(end -0.12065 -0.305054)
			(stroke
				(width 0.1)
				(type default)
			)
			(layer "F.Fab")
		)
		(fp_line
			(start -0.67945 0.3048)
			(end -0.67945 -0.305054)
			(stroke
				(width 0.1)
				(type default)
			)
			(layer "F.Fab")
		)
		(fp_line
			(start -0.12065 -0.305054)
			(end -0.12065 -0.2794)
			(stroke
				(width 0.1)
				(type default)
			)
			(layer "F.Fab")
		)
		(fp_line
			(start -0.12065 -0.2794)
			(end 0.12065 -0.2794)
			(stroke
				(width 0.1)
				(type default)
			)
			(layer "F.Fab")
		)
		(fp_line
			(start -0.12065 0.2794)
			(end -0.12065 0.3048)
			(stroke
				(width 0.1)
				(type default)
			)
			(layer "F.Fab")
		)
		(fp_line
			(start -0.12065 0.3048)
			(end -0.67945 0.3048)
			(stroke
				(width 0.1)
				(type default)
			)
			(layer "F.Fab")
		)
		(fp_line
			(start 0.120396 0.2794)
			(end -0.12065 0.2794)
			(stroke
				(width 0.1)
				(type default)
			)
			(layer "F.Fab")
		)
		(fp_line
			(start 0.120396 0.3048)
			(end 0.120396 0.2794)
			(stroke
				(width 0.1)
				(type default)
			)
			(layer "F.Fab")
		)
		(fp_line
			(start 0.12065 -0.3048)
			(end 0.67945 -0.3048)
			(stroke
				(width 0.1)
				(type default)
			)
			(layer "F.Fab")
		)
		(fp_line
			(start 0.12065 -0.2794)
			(end 0.12065 -0.3048)
			(stroke
				(width 0.1)
				(type default)
			)
			(layer "F.Fab")
		)
		(fp_line
			(start 0.67945 -0.3048)
			(end 0.67945 0.3048)
			(stroke
				(width 0.1)
				(type default)
			)
			(layer "F.Fab")
		)
		(fp_line
			(start 0.67945 0.3048)
			(end 0.120396 0.3048)
			(stroke
				(width 0.1)
				(type default)
			)
			(layer "F.Fab")
		)
		(pad "1" smd circle
			(at -0.40005 0)
			(size 0 0)
			(layers "F.Cu" "F.Mask" "F.Paste")
			(net "J7_P1")
		)
		(pad "2" smd circle
			(at 0.40005 0)
			(size 0 0)
			(layers "F.Cu" "F.Mask" "F.Paste")
			(net "GND")
		)
	)
	(footprint ""
		(layer "F.Cu")
		(at 60.579 -84.709 -90)
		(property "Reference" "R164"
			(at 0 0 270)
			(layer "F.SilkS")
			(hide yes)
			(effects
				(font
					(size 1.27 1.27)
				)
			)
		)
		(property "Value" ""
			(at 0 0 270)
			(layer "F.Fab")
			(effects
				(font
					(size 1.27 1.27)
				)
			)
		)
		(duplicate_pad_numbers_are_jumpers no)
		(fp_line
			(start -0.7874 0.4064)
			(end -0.7874 -0.4064)
			(stroke
				(width 0.1524)
				(type default)
			)
			(layer "F.SilkS")
		)
		(fp_line
			(start 0.7874 0.4064)
			(end -0.7874 0.4064)
			(stroke
				(width 0.1524)
				(type default)
			)
			(layer "F.SilkS")
		)
		(fp_line
			(start -0.7874 -0.4064)
			(end 0.7874 -0.4064)
			(stroke
				(width 0.1524)
				(type default)
			)
			(layer "F.SilkS")
		)
		(fp_line
			(start 0.7874 -0.4064)
			(end 0.7874 0.4064)
			(stroke
				(width 0.1524)
				(type default)
			)
			(layer "F.SilkS")
		)
		(fp_line
			(start -0.67945 0.3048)
			(end -0.67945 -0.305054)
			(stroke
				(width 0.1)
				(type default)
			)
			(layer "F.Fab")
		)
		(fp_line
			(start -0.12065 0.3048)
			(end -0.67945 0.3048)
			(stroke
				(width 0.1)
				(type default)
			)
			(layer "F.Fab")
		)
		(fp_line
			(start 0.120396 0.3048)
			(end 0.120396 0.2794)
			(stroke
				(width 0.1)
				(type default)
			)
			(layer "F.Fab")
		)
		(fp_line
			(start 0.67945 0.3048)
			(end 0.120396 0.3048)
			(stroke
				(width 0.1)
				(type default)
			)
			(layer "F.Fab")
		)
		(fp_line
			(start -0.12065 0.2794)
			(end -0.12065 0.3048)
			(stroke
				(width 0.1)
				(type default)
			)
			(layer "F.Fab")
		)
		(fp_line
			(start 0.120396 0.2794)
			(end -0.12065 0.2794)
			(stroke
				(width 0.1)
				(type default)
			)
			(layer "F.Fab")
		)
		(fp_line
			(start -0.12065 -0.2794)
			(end 0.12065 -0.2794)
			(stroke
				(width 0.1)
				(type default)
			)
			(layer "F.Fab")
		)
		(fp_line
			(start 0.12065 -0.2794)
			(end 0.12065 -0.3048)
			(stroke
				(width 0.1)
				(type default)
			)
			(layer "F.Fab")
		)
		(fp_line
			(start 0.12065 -0.3048)
			(end 0.67945 -0.3048)
			(stroke
				(width 0.1)
				(type default)
			)
			(layer "F.Fab")
		)
		(fp_line
			(start 0.67945 -0.3048)
			(end 0.67945 0.3048)
			(stroke
				(width 0.1)
				(type default)
			)
			(layer "F.Fab")
		)
		(fp_line
			(start -0.67945 -0.305054)
			(end -0.12065 -0.305054)
			(stroke
				(width 0.1)
				(type default)
			)
			(layer "F.Fab")
		)
		(fp_line
			(start -0.12065 -0.305054)
			(end -0.12065 -0.2794)
			(stroke
				(width 0.1)
				(type default)
			)
			(layer "F.Fab")
		)
		(pad "1" smd circle
			(at -0.40005 0 270)
			(size 0 0)
			(layers "F.Cu" "F.Mask" "F.Paste")
			(net "SPI_BMC_BOOT_MISO")
		)
		(pad "2" smd circle
			(at 0.40005 0 270)
			(size 0 0)
			(layers "F.Cu" "F.Mask" "F.Paste")
			(net "GND")
		)
	)
	(footprint ""
		(layer "F.Cu")
		(at 20.209764 -30.026864 180)
		(property "Reference" "PC264"
			(at 0 0 180)
			(layer "F.SilkS")
			(hide yes)
			(effects
				(font
					(size 1.27 1.27)
				)
			)
		)
		(property "Value" ""
			(at 0 0 180)
			(layer "F.Fab")
			(effects
				(font
					(size 1.27 1.27)
				)
			)
		)
		(duplicate_pad_numbers_are_jumpers no)
		(fp_line
			(start 0.7874 0.4064)
			(end -0.7874 0.4064)
			(stroke
				(width 0.1524)
				(type default)
			)
			(layer "F.SilkS")
		)
		(fp_line
			(start 0.7874 -0.4064)
			(end 0.7874 0.4064)
			(stroke
				(width 0.1524)
				(type default)
			)
			(layer "F.SilkS")
		)
		(fp_line
			(start -0.7874 0.4064)
			(end -0.7874 -0.4064)
			(stroke
				(width 0.1524)
				(type default)
			)
			(layer "F.SilkS")
		)
		(fp_line
			(start -0.7874 -0.4064)
			(end 0.7874 -0.4064)
			(stroke
				(width 0.1524)
				(type default)
			)
			(layer "F.SilkS")
		)
		(fp_line
			(start 0.67945 0.3048)
			(end 0.120396 0.3048)
			(stroke
				(width 0.1)
				(type default)
			)
			(layer "F.Fab")
		)
		(fp_line
			(start 0.67945 -0.3048)
			(end 0.67945 0.3048)
			(stroke
				(width 0.1)
				(type default)
			)
			(layer "F.Fab")
		)
		(fp_line
			(start 0.12065 -0.2794)
			(end 0.12065 -0.3048)
			(stroke
				(width 0.1)
				(type default)
			)
			(layer "F.Fab")
		)
		(fp_line
			(start 0.12065 -0.3048)
			(end 0.67945 -0.3048)
			(stroke
				(width 0.1)
				(type default)
			)
			(layer "F.Fab")
		)
		(fp_line
			(start 0.120396 0.3048)
			(end 0.120396 0.2794)
			(stroke
				(width 0.1)
				(type default)
			)
			(layer "F.Fab")
		)
		(fp_line
			(start 0.120396 0.2794)
			(end -0.12065 0.2794)
			(stroke
				(width 0.1)
				(type default)
			)
			(layer "F.Fab")
		)
		(fp_line
			(start -0.12065 0.3048)
			(end -0.67945 0.3048)
			(stroke
				(width 0.1)
				(type default)
			)
			(layer "F.Fab")
		)
		(fp_line
			(start -0.12065 0.2794)
			(end -0.12065 0.3048)
			(stroke
				(width 0.1)
				(type default)
			)
			(layer "F.Fab")
		)
		(fp_line
			(start -0.12065 -0.2794)
			(end 0.12065 -0.2794)
			(stroke
				(width 0.1)
				(type default)
			)
			(layer "F.Fab")
		)
		(fp_line
			(start -0.12065 -0.305054)
			(end -0.12065 -0.2794)
			(stroke
				(width 0.1)
				(type default)
			)
			(layer "F.Fab")
		)
		(fp_line
			(start -0.67945 0.3048)
			(end -0.67945 -0.305054)
			(stroke
				(width 0.1)
				(type default)
			)
			(layer "F.Fab")
		)
		(fp_line
			(start -0.67945 -0.305054)
			(end -0.12065 -0.305054)
			(stroke
				(width 0.1)
				(type default)
			)
			(layer "F.Fab")
		)
		(pad "1" smd circle
			(at -0.40005 0 180)
			(size 0 0)
			(layers "F.Cu" "F.Mask" "F.Paste")
			(net "SW_P1V0_AUX_BST")
		)
		(pad "2" smd circle
			(at 0.40005 0 180)
			(size 0 0)
			(layers "F.Cu" "F.Mask" "F.Paste")
			(net "SW_P1V0_AUX_SW")
		)
	)
	(footprint ""
		(layer "F.Cu")
		(at 66.167 -28.0162)
		(property "Reference" "R441"
			(at 0 0 0)
			(layer "F.SilkS")
			(hide yes)
			(effects
				(font
					(size 1.27 1.27)
				)
			)
		)
		(property "Value" ""
			(at 0 0 0)
			(layer "F.Fab")
			(effects
				(font
					(size 1.27 1.27)
				)
			)
		)
		(duplicate_pad_numbers_are_jumpers no)
		(fp_line
			(start -0.5588 -0.4064)
			(end 0.7874 -0.4064)
			(stroke
				(width 0.1524)
				(type default)
			)
			(layer "F.SilkS")
		)
		(fp_line
			(start 0.7874 -0.4064)
			(end 0.7874 0.4064)
			(stroke
				(width 0.1524)
				(type default)
			)
			(layer "F.SilkS")
		)
		(fp_line
			(start 0.7874 0.4064)
			(end -0.4318 0.4064)
			(stroke
				(width 0.1524)
				(type default)
			)
			(layer "F.SilkS")
		)
		(fp_line
			(start -0.67945 -0.305054)
			(end -0.12065 -0.305054)
			(stroke
				(width 0.1)
				(type default)
			)
			(layer "F.Fab")
		)
		(fp_line
			(start -0.67945 0.3048)
			(end -0.67945 -0.305054)
			(stroke
				(width 0.1)
				(type default)
			)
			(layer "F.Fab")
		)
		(fp_line
			(start -0.12065 -0.305054)
			(end -0.12065 -0.2794)
			(stroke
				(width 0.1)
				(type default)
			)
			(layer "F.Fab")
		)
		(fp_line
			(start -0.12065 -0.2794)
			(end 0.12065 -0.2794)
			(stroke
				(width 0.1)
				(type default)
			)
			(layer "F.Fab")
		)
		(fp_line
			(start -0.12065 0.2794)
			(end -0.12065 0.3048)
			(stroke
				(width 0.1)
				(type default)
			)
			(layer "F.Fab")
		)
		(fp_line
			(start -0.12065 0.3048)
			(end -0.67945 0.3048)
			(stroke
				(width 0.1)
				(type default)
			)
			(layer "F.Fab")
		)
		(fp_line
			(start 0.120396 0.2794)
			(end -0.12065 0.2794)
			(stroke
				(width 0.1)
				(type default)
			)
			(layer "F.Fab")
		)
		(fp_line
			(start 0.120396 0.3048)
			(end 0.120396 0.2794)
			(stroke
				(width 0.1)
				(type default)
			)
			(layer "F.Fab")
		)
		(fp_line
			(start 0.12065 -0.3048)
			(end 0.67945 -0.3048)
			(stroke
				(width 0.1)
				(type default)
			)
			(layer "F.Fab")
		)
		(fp_line
			(start 0.12065 -0.2794)
			(end 0.12065 -0.3048)
			(stroke
				(width 0.1)
				(type default)
			)
			(layer "F.Fab")
		)
		(fp_line
			(start 0.67945 -0.3048)
			(end 0.67945 0.3048)
			(stroke
				(width 0.1)
				(type default)
			)
			(layer "F.Fab")
		)
		(fp_line
			(start 0.67945 0.3048)
			(end 0.120396 0.3048)
			(stroke
				(width 0.1)
				(type default)
			)
			(layer "F.Fab")
		)
		(pad "1" smd circle
			(at -0.40005 0)
			(size 0 0)
			(layers "F.Cu" "F.Mask" "F.Paste")
			(net "USB_HOST_BMC_A_DN")
		)
		(pad "2" smd circle
			(at 0.40005 0)
			(size 0 0)
			(layers "F.Cu" "F.Mask" "F.Paste")
			(net "GND")
		)
	)
	(footprint ""
		(layer "F.Cu")
		(at 77.947774 -69.407024 180)
		(property "Reference" "PR496"
			(at 0 0 180)
			(layer "F.SilkS")
			(hide yes)
			(effects
				(font
					(size 1.27 1.27)
				)
			)
		)
		(property "Value" ""
			(at 0 0 180)
			(layer "F.Fab")
			(effects
				(font
					(size 1.27 1.27)
				)
			)
		)
		(duplicate_pad_numbers_are_jumpers no)
		(fp_line
			(start 0.7874 0.4064)
			(end -0.7874 0.4064)
			(stroke
				(width 0.1524)
				(type default)
			)
			(layer "F.SilkS")
		)
		(fp_line
			(start 0.7874 -0.4064)
			(end 0.7874 0.4064)
			(stroke
				(width 0.1524)
				(type default)
			)
			(layer "F.SilkS")
		)
		(fp_line
			(start -0.7874 0.4064)
			(end -0.7874 -0.4064)
			(stroke
				(width 0.1524)
				(type default)
			)
			(layer "F.SilkS")
		)
		(fp_line
			(start -0.7874 -0.4064)
			(end 0.7874 -0.4064)
			(stroke
				(width 0.1524)
				(type default)
			)
			(layer "F.SilkS")
		)
		(fp_line
			(start 0.67945 0.3048)
			(end 0.120396 0.3048)
			(stroke
				(width 0.1)
				(type default)
			)
			(layer "F.Fab")
		)
		(fp_line
			(start 0.67945 -0.3048)
			(end 0.67945 0.3048)
			(stroke
				(width 0.1)
				(type default)
			)
			(layer "F.Fab")
		)
		(fp_line
			(start 0.12065 -0.2794)
			(end 0.12065 -0.3048)
			(stroke
				(width 0.1)
				(type default)
			)
			(layer "F.Fab")
		)
		(fp_line
			(start 0.12065 -0.3048)
			(end 0.67945 -0.3048)
			(stroke
				(width 0.1)
				(type default)
			)
			(layer "F.Fab")
		)
		(fp_line
			(start 0.120396 0.3048)
			(end 0.120396 0.2794)
			(stroke
				(width 0.1)
				(type default)
			)
			(layer "F.Fab")
		)
		(fp_line
			(start 0.120396 0.2794)
			(end -0.12065 0.2794)
			(stroke
				(width 0.1)
				(type default)
			)
			(layer "F.Fab")
		)
		(fp_line
			(start -0.12065 0.3048)
			(end -0.67945 0.3048)
			(stroke
				(width 0.1)
				(type default)
			)
			(layer "F.Fab")
		)
		(fp_line
			(start -0.12065 0.2794)
			(end -0.12065 0.3048)
			(stroke
				(width 0.1)
				(type default)
			)
			(layer "F.Fab")
		)
		(fp_line
			(start -0.12065 -0.2794)
			(end 0.12065 -0.2794)
			(stroke
				(width 0.1)
				(type default)
			)
			(layer "F.Fab")
		)
		(fp_line
			(start -0.12065 -0.305054)
			(end -0.12065 -0.2794)
			(stroke
				(width 0.1)
				(type default)
			)
			(layer "F.Fab")
		)
		(fp_line
			(start -0.67945 0.3048)
			(end -0.67945 -0.305054)
			(stroke
				(width 0.1)
				(type default)
			)
			(layer "F.Fab")
		)
		(fp_line
			(start -0.67945 -0.305054)
			(end -0.12065 -0.305054)
			(stroke
				(width 0.1)
				(type default)
			)
			(layer "F.Fab")
		)
		(pad "1" smd circle
			(at -0.40005 0 180)
			(size 0 0)
			(layers "F.Cu" "F.Mask" "F.Paste")
			(net "P1V2_AUX_MODE")
		)
		(pad "2" smd circle
			(at 0.40005 0 180)
			(size 0 0)
			(layers "F.Cu" "F.Mask" "F.Paste")
			(net "GND")
		)
	)
)
